(kicad_pcb
	(version 20260206)
	(generator "pcbnew")
	(generator_version "10.0")
	(general
		(thickness 1.6)
		(legacy_teardrops no)
	)
	(paper "A4")
	(title_block
		(title "Bryce Canyon_IOM_M2_16342-2_OCP.brd")
		(comment 1 "Bryce Canyon / footprints 1107-1113 of 1146")
	)
	(layers
		(0 "F.Cu" signal "TOP")
		(4 "In1.Cu" signal "L2GND")
		(6 "In2.Cu" signal "L3")
		(8 "In3.Cu" signal "L4VCC")
		(10 "In4.Cu" signal "L5VCC")
		(12 "In5.Cu" signal "L6")
		(14 "In6.Cu" signal "L7GND")
		(2 "B.Cu" signal "BOTTOM")
		(9 "F.Adhes" user "F.Adhesive")
		(11 "B.Adhes" user "B.Adhesive")
		(13 "F.Paste" user "Package Geometry/Pastemask Top")
		(15 "B.Paste" user "Package Geometry/Pastemask Bottom")
		(5 "F.SilkS" user "Ref Des/Silkscreen Top")
		(7 "B.SilkS" user "Ref Des/Silkscreen Bottom")
		(1 "F.Mask" user "Board Geometry/Soldermask Top")
		(3 "B.Mask" user "Board Geometry/Soldermask Bottom")
		(17 "Dwgs.User" user "User.Drawings")
		(19 "Cmts.User" user "User.Comments")
		(21 "Eco1.User" user "User.Eco1")
		(23 "Eco2.User" user "User.Eco2")
		(25 "Edge.Cuts" user "Board Geometry/Outline")
		(27 "Margin" user)
		(31 "F.CrtYd" user "Package Geometry/Place Bound Top")
		(29 "B.CrtYd" user "Package Geometry/Place Bound Bottom")
		(35 "F.Fab" user "Ref Des/Assembly Top")
		(33 "B.Fab" user "Ref Des/Assembly Bottom")
	)
	(footprint ""
		(layer "B.Cu")
		(at 87.401908 -150.612602 180)
		(property "Reference" "R97"
			(at 0 0 0)
			(layer "B.SilkS")
			(hide yes)
			(effects
				(font
					(size 1.27 1.27)
				)
				(justify mirror)
			)
		)
		(property "Value" "0R2J-2-GP"
			(at -0.064008 -3.993896 180)
			(unlocked yes)
			(layer "B.Fab")
			(hide yes)
			(effects
				(font
					(size 1.016 1.016)
					(thickness 0.1524)
				)
				(justify mirror)
			)
		)
		(property "Device Type" "R402H16"
			(at -0.064008 -5.517896 180)
			(unlocked yes)
			(layer "B.Fab")
			(hide yes)
			(effects
				(font
					(size 1.016 1.016)
					(thickness 0.1524)
				)
				(justify mirror)
			)
		)
		(duplicate_pad_numbers_are_jumpers no)
		(fp_line
			(start 0.508 -0.9398)
			(end 0.508 0.9398)
			(stroke
				(width 0.1524)
				(type default)
			)
			(layer "B.SilkS")
		)
		(fp_line
			(start -0.508 -0.9398)
			(end 0.508 -0.9398)
			(stroke
				(width 0.1524)
				(type default)
			)
			(layer "B.SilkS")
		)
		(fp_rect
			(start 0.508 0.9398)
			(end -0.508 -0.9398)
			(stroke
				(width 0)
				(type default)
			)
			(fill no)
			(layer "B.CrtYd")
		)
		(fp_rect
			(start 0.508 0.9398)
			(end -0.508 -0.9398)
			(stroke
				(width 0)
				(type default)
			)
			(fill no)
			(layer "B.Fab")
		)
		(pad "1" smd custom
			(at 0 -0.4445)
			(size 0.1397 0.1397)
			(layers "B.Cu" "B.Mask" "B.Paste")
			(net "I2C_BMC_COMP_SDA_OUT")
			(options
				(clearance outline)
				(anchor circle)
			)
			(primitives
				(gr_poly
					(pts
						(arc
							(start -0.1778 0.2794)
							(mid -0.249642 0.249642)
							(end -0.2794 0.1778)
						)
						(arc
							(start -0.2794 -0.1778)
							(mid -0.249642 -0.249642)
							(end -0.1778 -0.2794)
						)
						(arc
							(start 0.1778 -0.2794)
							(mid 0.249642 -0.249642)
							(end 0.2794 -0.1778)
						)
						(arc
							(start 0.2794 0.1778)
							(mid 0.249642 0.249642)
							(end 0.1778 0.2794)
						)
					)
					(width 0)
					(fill yes)
				)
			)
		)
		(pad "2" smd custom
			(at 0 0.4445)
			(size 0.1397 0.1397)
			(layers "B.Cu" "B.Mask" "B.Paste")
			(net "I2C_BMC_COMP_SDA_R")
			(options
				(clearance outline)
				(anchor circle)
			)
			(primitives
				(gr_poly
					(pts
						(arc
							(start -0.1778 0.2794)
							(mid -0.249642 0.249642)
							(end -0.2794 0.1778)
						)
						(arc
							(start -0.2794 -0.1778)
							(mid -0.249642 -0.249642)
							(end -0.1778 -0.2794)
						)
						(arc
							(start 0.1778 -0.2794)
							(mid 0.249642 -0.249642)
							(end 0.2794 -0.1778)
						)
						(arc
							(start 0.2794 0.1778)
							(mid 0.249642 0.249642)
							(end 0.1778 0.2794)
						)
					)
					(width 0)
					(fill yes)
				)
			)
		)
	)
	(footprint ""
		(layer "B.Cu")
		(at 26.079196 -136.099296 90)
		(property "Reference" "C64"
			(at 0 0 90)
			(layer "B.SilkS")
			(hide yes)
			(effects
				(font
					(size 1.27 1.27)
				)
				(justify mirror)
			)
		)
		(property "Value" "SC1U16V3KX-5GP"
			(at 0 -2.8194 90)
			(unlocked yes)
			(layer "B.Fab")
			(hide yes)
			(effects
				(font
					(size 1.016 1.016)
					(thickness 0.1524)
				)
				(justify mirror)
			)
		)
		(property "Device Type" "C603H36"
			(at 0 -4.3434 90)
			(unlocked yes)
			(layer "B.Fab")
			(hide yes)
			(effects
				(font
					(size 1.016 1.016)
					(thickness 0.1524)
				)
				(justify mirror)
			)
		)
		(duplicate_pad_numbers_are_jumpers no)
		(fp_line
			(start -0.508 0)
			(end 0.508 0)
			(stroke
				(width 0.2032)
				(type default)
			)
			(layer "B.SilkS")
		)
		(fp_rect
			(start 0.5842 1.3335)
			(end -0.5842 -1.3335)
			(stroke
				(width 0)
				(type default)
			)
			(fill no)
			(layer "B.CrtYd")
		)
		(fp_rect
			(start 0.5842 1.3335)
			(end -0.5842 -1.3335)
			(stroke
				(width 0)
				(type default)
			)
			(fill no)
			(layer "B.Fab")
		)
		(pad "1" smd custom
			(at 0 -0.762 270)
			(size 0.2159 0.2159)
			(layers "B.Cu" "B.Mask" "B.Paste")
			(net "P2V5_STBY")
			(options
				(clearance outline)
				(anchor circle)
			)
			(primitives
				(gr_poly
					(pts
						(arc
							(start -0.3302 0.4318)
							(mid -0.402042 0.402042)
							(end -0.4318 0.3302)
						)
						(arc
							(start -0.4318 -0.3302)
							(mid -0.402042 -0.402042)
							(end -0.3302 -0.4318)
						)
						(arc
							(start 0.3302 -0.4318)
							(mid 0.402042 -0.402042)
							(end 0.4318 -0.3302)
						)
						(arc
							(start 0.4318 0.3302)
							(mid 0.402042 0.402042)
							(end 0.3302 0.4318)
						)
					)
					(width 0)
					(fill yes)
				)
			)
		)
		(pad "2" smd custom
			(at 0 0.762 270)
			(size 0.2159 0.2159)
			(layers "B.Cu" "B.Mask" "B.Paste")
			(net "GND")
			(options
				(clearance outline)
				(anchor circle)
			)
			(primitives
				(gr_poly
					(pts
						(arc
							(start -0.3302 0.4318)
							(mid -0.402042 0.402042)
							(end -0.4318 0.3302)
						)
						(arc
							(start -0.4318 -0.3302)
							(mid -0.402042 -0.402042)
							(end -0.3302 -0.4318)
						)
						(arc
							(start 0.3302 -0.4318)
							(mid 0.402042 -0.402042)
							(end 0.4318 -0.3302)
						)
						(arc
							(start 0.4318 0.3302)
							(mid 0.402042 0.402042)
							(end 0.3302 0.4318)
						)
					)
					(width 0)
					(fill yes)
				)
			)
		)
	)
	(footprint ""
		(layer "B.Cu")
		(at 52.0192 -124.1552)
		(property "Reference" "R403"
			(at 0 0 0)
			(layer "B.SilkS")
			(hide yes)
			(effects
				(font
					(size 1.27 1.27)
				)
				(justify mirror)
			)
		)
		(property "Value" "0R2J-2-GP"
			(at -0.064008 -3.993896 0)
			(unlocked yes)
			(layer "B.Fab")
			(hide yes)
			(effects
				(font
					(size 1.016 1.016)
					(thickness 0.1524)
				)
				(justify mirror)
			)
		)
		(property "Device Type" "R402H16"
			(at -0.064008 -5.517896 0)
			(unlocked yes)
			(layer "B.Fab")
			(hide yes)
			(effects
				(font
					(size 1.016 1.016)
					(thickness 0.1524)
				)
				(justify mirror)
			)
		)
		(duplicate_pad_numbers_are_jumpers no)
		(fp_line
			(start -0.508 -0.9398)
			(end 0.508 -0.9398)
			(stroke
				(width 0.1524)
				(type default)
			)
			(layer "B.SilkS")
		)
		(fp_line
			(start 0.508 -0.9398)
			(end 0.508 0.9398)
			(stroke
				(width 0.1524)
				(type default)
			)
			(layer "B.SilkS")
		)
		(fp_rect
			(start 0.508 0.9398)
			(end -0.508 -0.9398)
			(stroke
				(width 0)
				(type default)
			)
			(fill no)
			(layer "B.CrtYd")
		)
		(fp_rect
			(start 0.508 0.9398)
			(end -0.508 -0.9398)
			(stroke
				(width 0)
				(type default)
			)
			(fill no)
			(layer "B.Fab")
		)
		(pad "1" smd custom
			(at 0 -0.4445 180)
			(size 0.1397 0.1397)
			(layers "B.Cu" "B.Mask" "B.Paste")
			(net "M2_1_ALERT#_R")
			(options
				(clearance outline)
				(anchor circle)
			)
			(primitives
				(gr_poly
					(pts
						(arc
							(start -0.1778 0.2794)
							(mid -0.249642 0.249642)
							(end -0.2794 0.1778)
						)
						(arc
							(start -0.2794 -0.1778)
							(mid -0.249642 -0.249642)
							(end -0.1778 -0.2794)
						)
						(arc
							(start 0.1778 -0.2794)
							(mid 0.249642 -0.249642)
							(end 0.2794 -0.1778)
						)
						(arc
							(start 0.2794 0.1778)
							(mid 0.249642 0.249642)
							(end 0.1778 0.2794)
						)
					)
					(width 0)
					(fill yes)
				)
			)
		)
		(pad "2" smd custom
			(at 0 0.4445 180)
			(size 0.1397 0.1397)
			(layers "B.Cu" "B.Mask" "B.Paste")
			(net "M2_1_ALERT#")
			(options
				(clearance outline)
				(anchor circle)
			)
			(primitives
				(gr_poly
					(pts
						(arc
							(start -0.1778 0.2794)
							(mid -0.249642 0.249642)
							(end -0.2794 0.1778)
						)
						(arc
							(start -0.2794 -0.1778)
							(mid -0.249642 -0.249642)
							(end -0.1778 -0.2794)
						)
						(arc
							(start 0.1778 -0.2794)
							(mid 0.249642 -0.249642)
							(end 0.2794 -0.1778)
						)
						(arc
							(start 0.2794 0.1778)
							(mid 0.249642 0.249642)
							(end 0.1778 0.2794)
						)
					)
					(width 0)
					(fill yes)
				)
			)
		)
	)
	(footprint ""
		(layer "B.Cu")
		(at 79.248 -168.91 180)
		(property "Reference" "R452"
			(at 0 0 0)
			(layer "B.SilkS")
			(hide yes)
			(effects
				(font
					(size 1.27 1.27)
				)
				(justify mirror)
			)
		)
		(property "Value" "0R2J-2-GP"
			(at -0.064008 -3.993896 180)
			(unlocked yes)
			(layer "B.Fab")
			(hide yes)
			(effects
				(font
					(size 1.016 1.016)
					(thickness 0.1524)
				)
				(justify mirror)
			)
		)
		(property "Device Type" "R402H16"
			(at -0.064008 -5.517896 180)
			(unlocked yes)
			(layer "B.Fab")
			(hide yes)
			(effects
				(font
					(size 1.016 1.016)
					(thickness 0.1524)
				)
				(justify mirror)
			)
		)
		(duplicate_pad_numbers_are_jumpers no)
		(fp_line
			(start 0.508 -0.9398)
			(end 0.508 0.9398)
			(stroke
				(width 0.1524)
				(type default)
			)
			(layer "B.SilkS")
		)
		(fp_line
			(start -0.508 -0.9398)
			(end 0.508 -0.9398)
			(stroke
				(width 0.1524)
				(type default)
			)
			(layer "B.SilkS")
		)
		(fp_rect
			(start 0.508 0.9398)
			(end -0.508 -0.9398)
			(stroke
				(width 0)
				(type default)
			)
			(fill no)
			(layer "B.CrtYd")
		)
		(fp_rect
			(start 0.508 0.9398)
			(end -0.508 -0.9398)
			(stroke
				(width 0)
				(type default)
			)
			(fill no)
			(layer "B.Fab")
		)
		(pad "1" smd custom
			(at 0 -0.4445)
			(size 0.1397 0.1397)
			(layers "B.Cu" "B.Mask" "B.Paste")
			(net "UART_SDB_TX_R")
			(options
				(clearance outline)
				(anchor circle)
			)
			(primitives
				(gr_poly
					(pts
						(arc
							(start -0.1778 0.2794)
							(mid -0.249642 0.249642)
							(end -0.2794 0.1778)
						)
						(arc
							(start -0.2794 -0.1778)
							(mid -0.249642 -0.249642)
							(end -0.1778 -0.2794)
						)
						(arc
							(start 0.1778 -0.2794)
							(mid 0.249642 -0.249642)
							(end 0.2794 -0.1778)
						)
						(arc
							(start 0.2794 0.1778)
							(mid 0.249642 0.249642)
							(end 0.1778 0.2794)
						)
					)
					(width 0)
					(fill yes)
				)
			)
		)
		(pad "2" smd custom
			(at 0 0.4445)
			(size 0.1397 0.1397)
			(layers "B.Cu" "B.Mask" "B.Paste")
			(net "UART_SDB_TX")
			(options
				(clearance outline)
				(anchor circle)
			)
			(primitives
				(gr_poly
					(pts
						(arc
							(start -0.1778 0.2794)
							(mid -0.249642 0.249642)
							(end -0.2794 0.1778)
						)
						(arc
							(start -0.2794 -0.1778)
							(mid -0.249642 -0.249642)
							(end -0.1778 -0.2794)
						)
						(arc
							(start 0.1778 -0.2794)
							(mid 0.249642 -0.249642)
							(end 0.2794 -0.1778)
						)
						(arc
							(start 0.2794 0.1778)
							(mid 0.249642 0.249642)
							(end 0.1778 0.2794)
						)
					)
					(width 0)
					(fill yes)
				)
			)
		)
	)
	(footprint ""
		(layer "B.Cu")
		(at 50.419 -124.333 90)
		(property "Reference" "R406"
			(at 0 0 90)
			(layer "B.SilkS")
			(hide yes)
			(effects
				(font
					(size 1.27 1.27)
				)
				(justify mirror)
			)
		)
		(property "Value" "0R2J-2-GP"
			(at -0.064008 -3.993896 90)
			(unlocked yes)
			(layer "B.Fab")
			(hide yes)
			(effects
				(font
					(size 1.016 1.016)
					(thickness 0.1524)
				)
				(justify mirror)
			)
		)
		(property "Device Type" "R402H16"
			(at -0.064008 -5.517896 90)
			(unlocked yes)
			(layer "B.Fab")
			(hide yes)
			(effects
				(font
					(size 1.016 1.016)
					(thickness 0.1524)
				)
				(justify mirror)
			)
		)
		(duplicate_pad_numbers_are_jumpers no)
		(fp_line
			(start 0.508 -0.9398)
			(end 0.508 0.9398)
			(stroke
				(width 0.1524)
				(type default)
			)
			(layer "B.SilkS")
		)
		(fp_line
			(start -0.508 -0.9398)
			(end 0.508 -0.9398)
			(stroke
				(width 0.1524)
				(type default)
			)
			(layer "B.SilkS")
		)
		(fp_rect
			(start 0.508 0.9398)
			(end -0.508 -0.9398)
			(stroke
				(width 0)
				(type default)
			)
			(fill no)
			(layer "B.CrtYd")
		)
		(fp_rect
			(start 0.508 0.9398)
			(end -0.508 -0.9398)
			(stroke
				(width 0)
				(type default)
			)
			(fill no)
			(layer "B.Fab")
		)
		(pad "1" smd custom
			(at 0 -0.4445 270)
			(size 0.1397 0.1397)
			(layers "B.Cu" "B.Mask" "B.Paste")
			(net "M2_2_ALERT#_R")
			(options
				(clearance outline)
				(anchor circle)
			)
			(primitives
				(gr_poly
					(pts
						(arc
							(start -0.1778 0.2794)
							(mid -0.249642 0.249642)
							(end -0.2794 0.1778)
						)
						(arc
							(start -0.2794 -0.1778)
							(mid -0.249642 -0.249642)
							(end -0.1778 -0.2794)
						)
						(arc
							(start 0.1778 -0.2794)
							(mid 0.249642 -0.249642)
							(end 0.2794 -0.1778)
						)
						(arc
							(start 0.2794 0.1778)
							(mid 0.249642 0.249642)
							(end 0.1778 0.2794)
						)
					)
					(width 0)
					(fill yes)
				)
			)
		)
		(pad "2" smd custom
			(at 0 0.4445 270)
			(size 0.1397 0.1397)
			(layers "B.Cu" "B.Mask" "B.Paste")
			(net "M2_2_ALERT#")
			(options
				(clearance outline)
				(anchor circle)
			)
			(primitives
				(gr_poly
					(pts
						(arc
							(start -0.1778 0.2794)
							(mid -0.249642 0.249642)
							(end -0.2794 0.1778)
						)
						(arc
							(start -0.2794 -0.1778)
							(mid -0.249642 -0.249642)
							(end -0.1778 -0.2794)
						)
						(arc
							(start 0.1778 -0.2794)
							(mid 0.249642 -0.249642)
							(end 0.2794 -0.1778)
						)
						(arc
							(start 0.2794 0.1778)
							(mid 0.249642 0.249642)
							(end 0.1778 0.2794)
						)
					)
					(width 0)
					(fill yes)
				)
			)
		)
	)
	(footprint ""
		(layer "B.Cu")
		(at 44.141898 -149.135338 90)
		(property "Reference" "R143"
			(at 0 0 90)
			(layer "B.SilkS")
			(hide yes)
			(effects
				(font
					(size 1.27 1.27)
				)
				(justify mirror)
			)
		)
		(property "Value" "1KR2D-1-GP"
			(at -0.064008 -3.993896 90)
			(unlocked yes)
			(layer "B.Fab")
			(hide yes)
			(effects
				(font
					(size 1.016 1.016)
					(thickness 0.1524)
				)
				(justify mirror)
			)
		)
		(property "Device Type" "R402H16"
			(at -0.064008 -5.517896 90)
			(unlocked yes)
			(layer "B.Fab")
			(hide yes)
			(effects
				(font
					(size 1.016 1.016)
					(thickness 0.1524)
				)
				(justify mirror)
			)
		)
		(duplicate_pad_numbers_are_jumpers no)
		(fp_line
			(start 0.508 -0.9398)
			(end 0.508 0.9398)
			(stroke
				(width 0.1524)
				(type default)
			)
			(layer "B.SilkS")
		)
		(fp_line
			(start -0.508 -0.9398)
			(end 0.508 -0.9398)
			(stroke
				(width 0.1524)
				(type default)
			)
			(layer "B.SilkS")
		)
		(fp_rect
			(start 0.508 0.9398)
			(end -0.508 -0.9398)
			(stroke
				(width 0)
				(type default)
			)
			(fill no)
			(layer "B.CrtYd")
		)
		(fp_rect
			(start 0.508 0.9398)
			(end -0.508 -0.9398)
			(stroke
				(width 0)
				(type default)
			)
			(fill no)
			(layer "B.Fab")
		)
		(pad "1" smd custom
			(at 0 -0.4445 270)
			(size 0.1397 0.1397)
			(layers "B.Cu" "B.Mask" "B.Paste")
			(net "DDR_VREF")
			(options
				(clearance outline)
				(anchor circle)
			)
			(primitives
				(gr_poly
					(pts
						(arc
							(start -0.1778 0.2794)
							(mid -0.249642 0.249642)
							(end -0.2794 0.1778)
						)
						(arc
							(start -0.2794 -0.1778)
							(mid -0.249642 -0.249642)
							(end -0.1778 -0.2794)
						)
						(arc
							(start 0.1778 -0.2794)
							(mid 0.249642 -0.249642)
							(end 0.2794 -0.1778)
						)
						(arc
							(start 0.2794 0.1778)
							(mid 0.249642 0.249642)
							(end 0.1778 0.2794)
						)
					)
					(width 0)
					(fill yes)
				)
			)
		)
		(pad "2" smd custom
			(at 0 0.4445 270)
			(size 0.1397 0.1397)
			(layers "B.Cu" "B.Mask" "B.Paste")
			(net "GND")
			(options
				(clearance outline)
				(anchor circle)
			)
			(primitives
				(gr_poly
					(pts
						(arc
							(start -0.1778 0.2794)
							(mid -0.249642 0.249642)
							(end -0.2794 0.1778)
						)
						(arc
							(start -0.2794 -0.1778)
							(mid -0.249642 -0.249642)
							(end -0.1778 -0.2794)
						)
						(arc
							(start 0.1778 -0.2794)
							(mid 0.249642 -0.249642)
							(end 0.2794 -0.1778)
						)
						(arc
							(start 0.2794 0.1778)
							(mid 0.249642 0.249642)
							(end 0.1778 0.2794)
						)
					)
					(width 0)
					(fill yes)
				)
			)
		)
	)
	(footprint ""
		(layer "B.Cu")
		(at 216.386918 -97.327974 90)
		(property "Reference" "G10"
			(at 0 0 90)
			(layer "B.SilkS")
			(hide yes)
			(effects
				(font
					(size 1.27 1.27)
				)
				(justify mirror)
			)
		)
		(property "Value" "COPPER-CLOSE-GP-U"
			(at -0.0762 -2.8702 90)
			(unlocked yes)
			(layer "B.Fab")
			(hide yes)
			(effects
				(font
					(size 1.016 1.016)
					(thickness 0.1524)
				)
				(justify mirror)
			)
		)
		(property "Device Type" "CON2C-U"
			(at -0.0762 -4.3942 90)
			(unlocked yes)
			(layer "B.Fab")
			(hide yes)
			(effects
				(font
					(size 1.016 1.016)
					(thickness 0.1524)
				)
				(justify mirror)
			)
		)
		(duplicate_pad_numbers_are_jumpers no)
		(fp_rect
			(start 0.9398 0.9652)
			(end -0.9398 -0.9652)
			(stroke
				(width 0)
				(type default)
			)
			(fill no)
			(layer "B.CrtYd")
		)
		(fp_rect
			(start 0.9398 0.9652)
			(end -0.9398 -0.9652)
			(stroke
				(width 0)
				(type default)
			)
			(fill no)
			(layer "B.Fab")
		)
		(pad "1" smd custom
			(at 0 -0.5334 270)
			(size 0.17145 0.17145)
			(layers "B.Cu" "B.Mask" "B.Paste")
			(net "AGND_P3V3_M2")
			(options
				(clearance outline)
				(anchor circle)
			)
			(primitives
				(gr_poly
					(pts
						(xy -0.127 -0.3429) (xy -0.127 -0.1651) (xy -0.635 0.3429) (xy 0.635 0.3429) (xy 0.127 -0.1651)
						(xy 0.127 -0.3429)
					)
					(width 0)
					(fill yes)
				)
			)
		)
		(pad "2" smd custom
			(at 0 0.5334 270)
			(size 0.17145 0.17145)
			(layers "B.Cu" "B.Mask" "B.Paste")
			(net "GND")
			(options
				(clearance outline)
				(anchor circle)
			)
			(primitives
				(gr_poly
					(pts
						(xy -0.635 -0.3429) (xy -0.127 0.1651) (xy -0.127 0.3429) (xy 0.127 0.3429) (xy 0.127 0.1651)
						(xy 0.635 -0.3429)
					)
					(width 0)
					(fill yes)
				)
			)
		)
	)
)
